# T6G (Grand Teton) — schematic netlist excerpt (pin names and nets, part order shuffled) for the footprints in the layout excerpt that follows; sources: Cadence DE-HDL packaged netlist, KiCad conversion of 04192023_DAF0TMB3IC0_F0TG_MB_C_brd_V02_OCP.brd

C6501  Q_CAP_DIFFBUS  DIFF BUS_0.22UF 6.3V 20% X6S  pkg C0201  page 275 : \1\ = P5E_CPU0_P0_TX_BUF_C_DP<0> ; \2\ = P5E_CPU0_P0_TX_BUF_DP<0>
PC6551_09P0_2  Q_CAP  2.2UF 10V 10% X6S  pkg C0402  page 363 : A = P0V9_RETIMER_CPU0_PVCC ; B = GND
R619  Q_RES  0 5% CHIP  pkg 0201LF  page 342 : A = CLK_100M_RETIMER_CPU1_P2_R_DP ; B = CLK_100M_RETIMER_CPU1_P2_DP

(kicad_pcb
	(version 20260206)
	(generator "pcbnew")
	(generator_version "10.0")
	(general
		(thickness 1.6)
		(legacy_teardrops no)
	)
	(paper "A4")
	(title_block
		(title "04192023_DAF0TMB3IC0_F0TG_MB_C_brd_V02_OCP.brd")
		(comment 1 "Grand Teton / footprints 2769-2771 of 8354")
	)
	(layers
		(0 "F.Cu" signal "TOP")
		(4 "In1.Cu" signal "GND")
		(6 "In2.Cu" signal "IN1")
		(8 "In3.Cu" signal "GND1")
		(10 "In4.Cu" signal "IN2")
		(12 "In5.Cu" signal "GND2")
		(14 "In6.Cu" signal "IN3")
		(16 "In7.Cu" signal "GND3")
		(18 "In8.Cu" signal "VCC")
		(20 "In9.Cu" signal "VCC1")
		(22 "In10.Cu" signal "GND4")
		(24 "In11.Cu" signal "IN4")
		(26 "In12.Cu" signal "GND5")
		(28 "In13.Cu" signal "IN5")
		(30 "In14.Cu" signal "GND6")
		(32 "In15.Cu" signal "IN6")
		(34 "In16.Cu" signal "GND7")
		(2 "B.Cu" signal "BOTTOM")
		(9 "F.Adhes" user "F.Adhesive")
		(11 "B.Adhes" user "B.Adhesive")
		(13 "F.Paste" user "Package Geometry/Pastemask Top")
		(15 "B.Paste" user "Package Geometry/Pastemask Bottom")
		(5 "F.SilkS" user "Ref Des/Silkscreen Top")
		(7 "B.SilkS" user "Ref Des/Silkscreen Bottom")
		(1 "F.Mask" user "Board Geometry/Soldermask Top")
		(3 "B.Mask" user "Board Geometry/Soldermask Bottom")
		(17 "Dwgs.User" user "User.Drawings")
		(19 "Cmts.User" user "User.Comments")
		(21 "Eco1.User" user "User.Eco1")
		(23 "Eco2.User" user "User.Eco2")
		(25 "Edge.Cuts" user "Board Geometry/Outline")
		(27 "Margin" user)
		(31 "F.CrtYd" user "Package Geometry/Place Bound Top")
		(29 "B.CrtYd" user "Package Geometry/Place Bound Bottom")
		(35 "F.Fab" user "Ref Des/Assembly Top")
		(33 "B.Fab" user "Ref Des/Assembly Bottom")
	)
	(footprint ""
		(layer "F.Cu")
		(at 450.508878 -397.562578 -90)
		(property "Reference" "PC6551_09P0_2"
			(at 0 0 270)
			(layer "F.SilkS")
			(hide yes)
			(effects
				(font
					(size 1.27 1.27)
				)
			)
		)
		(property "Value" ""
			(at 0 0 270)
			(layer "F.Fab")
			(effects
				(font
					(size 1.27 1.27)
				)
			)
		)
		(duplicate_pad_numbers_are_jumpers no)
		(fp_line
			(start -0.7874 0.4064)
			(end -0.7874 -0.4064)
			(stroke
				(width 0.1524)
				(type default)
			)
			(layer "F.SilkS")
		)
		(fp_line
			(start 0.7874 0.4064)
			(end -0.7874 0.4064)
			(stroke
				(width 0.1524)
				(type default)
			)
			(layer "F.SilkS")
		)
		(fp_line
			(start -0.7874 -0.4064)
			(end 0.7874 -0.4064)
			(stroke
				(width 0.1524)
				(type default)
			)
			(layer "F.SilkS")
		)
		(fp_line
			(start 0.7874 -0.4064)
			(end 0.7874 0.4064)
			(stroke
				(width 0.1524)
				(type default)
			)
			(layer "F.SilkS")
		)
		(fp_line
			(start -0.67945 0.3048)
			(end -0.67945 -0.305054)
			(stroke
				(width 0.1)
				(type default)
			)
			(layer "F.Fab")
		)
		(fp_line
			(start -0.12065 0.3048)
			(end -0.67945 0.3048)
			(stroke
				(width 0.1)
				(type default)
			)
			(layer "F.Fab")
		)
		(fp_line
			(start 0.120396 0.3048)
			(end 0.120396 0.2794)
			(stroke
				(width 0.1)
				(type default)
			)
			(layer "F.Fab")
		)
		(fp_line
			(start 0.67945 0.3048)
			(end 0.120396 0.3048)
			(stroke
				(width 0.1)
				(type default)
			)
			(layer "F.Fab")
		)
		(fp_line
			(start -0.12065 0.2794)
			(end -0.12065 0.3048)
			(stroke
				(width 0.1)
				(type default)
			)
			(layer "F.Fab")
		)
		(fp_line
			(start 0.120396 0.2794)
			(end -0.12065 0.2794)
			(stroke
				(width 0.1)
				(type default)
			)
			(layer "F.Fab")
		)
		(fp_line
			(start -0.12065 -0.2794)
			(end 0.12065 -0.2794)
			(stroke
				(width 0.1)
				(type default)
			)
			(layer "F.Fab")
		)
		(fp_line
			(start 0.12065 -0.2794)
			(end 0.12065 -0.3048)
			(stroke
				(width 0.1)
				(type default)
			)
			(layer "F.Fab")
		)
		(fp_line
			(start 0.12065 -0.3048)
			(end 0.67945 -0.3048)
			(stroke
				(width 0.1)
				(type default)
			)
			(layer "F.Fab")
		)
		(fp_line
			(start 0.67945 -0.3048)
			(end 0.67945 0.3048)
			(stroke
				(width 0.1)
				(type default)
			)
			(layer "F.Fab")
		)
		(fp_line
			(start -0.67945 -0.305054)
			(end -0.12065 -0.305054)
			(stroke
				(width 0.1)
				(type default)
			)
			(layer "F.Fab")
		)
		(fp_line
			(start -0.12065 -0.305054)
			(end -0.12065 -0.2794)
			(stroke
				(width 0.1)
				(type default)
			)
			(layer "F.Fab")
		)
		(pad "1" smd circle
			(at -0.40005 0 270)
			(size 0 0)
			(layers "F.Cu" "F.Mask" "F.Paste")
			(net "P0V9_RETIMER_CPU0_PVCC")
		)
		(pad "2" smd circle
			(at 0.40005 0 270)
			(size 0 0)
			(layers "F.Cu" "F.Mask" "F.Paste")
			(net "GND")
		)
	)
	(footprint ""
		(layer "F.Cu")
		(at 304.682906 -416.899344 -90)
		(property "Reference" "C6501"
			(at 0 0 270)
			(layer "F.SilkS")
			(hide yes)
			(effects
				(font
					(size 1.27 1.27)
				)
			)
		)
		(property "Value" ""
			(at 0 0 270)
			(layer "F.Fab")
			(effects
				(font
					(size 1.27 1.27)
				)
			)
		)
		(duplicate_pad_numbers_are_jumpers no)
		(fp_line
			(start -0.299974 0.150114)
			(end -0.299974 -0.150114)
			(stroke
				(width 0.1)
				(type default)
			)
			(layer "F.Fab")
		)
		(fp_line
			(start 0.299974 0.150114)
			(end -0.299974 0.150114)
			(stroke
				(width 0.1)
				(type default)
			)
			(layer "F.Fab")
		)
		(fp_line
			(start -0.299974 -0.150114)
			(end 0.299974 -0.150114)
			(stroke
				(width 0.1)
				(type default)
			)
			(layer "F.Fab")
		)
		(fp_line
			(start 0.299974 -0.150114)
			(end 0.299974 0.150114)
			(stroke
				(width 0.1)
				(type default)
			)
			(layer "F.Fab")
		)
		(pad "1" smd rect
			(at -0.2667 0 270)
			(size 0.3048 0.381)
			(layers "F.Cu" "F.Mask" "F.Paste")
			(net "P5E_CPU0_P0_TX_BUF_C_DP<0>")
		)
		(pad "2" smd rect
			(at 0.2667 0 270)
			(size 0.3048 0.381)
			(layers "F.Cu" "F.Mask" "F.Paste")
			(net "P5E_CPU0_P0_TX_BUF_DP<0>")
		)
	)
	(footprint ""
		(layer "F.Cu")
		(at 142.155672 -387.764274)
		(property "Reference" "R619"
			(at 0 0 0)
			(layer "F.SilkS")
			(hide yes)
			(effects
				(font
					(size 1.27 1.27)
				)
			)
		)
		(property "Value" ""
			(at 0 0 0)
			(layer "F.Fab")
			(effects
				(font
					(size 1.27 1.27)
				)
			)
		)
		(duplicate_pad_numbers_are_jumpers no)
		(fp_line
			(start -0.32512 -0.175006)
			(end 0.32512 -0.175006)
			(stroke
				(width 0.1)
				(type default)
			)
			(layer "F.Fab")
		)
		(fp_line
			(start -0.32512 0.175006)
			(end -0.32512 -0.175006)
			(stroke
				(width 0.1)
				(type default)
			)
			(layer "F.Fab")
		)
		(fp_line
			(start 0.32512 -0.175006)
			(end 0.32512 0.175006)
			(stroke
				(width 0.1)
				(type default)
			)
			(layer "F.Fab")
		)
		(fp_line
			(start 0.32512 0.175006)
			(end -0.32512 0.175006)
			(stroke
				(width 0.1)
				(type default)
			)
			(layer "F.Fab")
		)
		(pad "1" smd rect
			(at -0.2667 0)
			(size 0.3048 0.381)
			(layers "F.Cu" "F.Mask" "F.Paste")
			(net "CLK_100M_RETIMER_CPU1_P2_R_DP")
		)
		(pad "2" smd rect
			(at 0.2667 0 180)
			(size 0.3048 0.381)
			(layers "F.Cu" "F.Mask" "F.Paste")
			(net "CLK_100M_RETIMER_CPU1_P2_DP")
		)
	)
)
